(kicad_pcb
	(version 20241229)
	(generator "pcbnew")
	(generator_version "9.0")
	(general
		(thickness 1.294)
		(legacy_teardrops no)
	)
	(paper "A3")
	(title_block
		(title "Kintex 410T devboard")
		(date "2024-04-03")
		(rev "1.1.2")
		(comment 9 "footprints 783-788 of 975")
	)
	(layers
		(0 "F.Cu" mixed)
		(4 "In1.Cu" power)
		(6 "In2.Cu" power)
		(8 "In3.Cu" mixed)
		(10 "In4.Cu" power)
		(12 "In5.Cu" mixed)
		(14 "In6.Cu" power)
		(16 "In7.Cu" mixed)
		(18 "In8.Cu" power)
		(2 "B.Cu" mixed)
		(9 "F.Adhes" user "F.Adhesive")
		(11 "B.Adhes" user "B.Adhesive")
		(13 "F.Paste" user)
		(15 "B.Paste" user)
		(5 "F.SilkS" user "F.Silkscreen")
		(7 "B.SilkS" user "B.Silkscreen")
		(1 "F.Mask" user)
		(3 "B.Mask" user)
		(17 "Dwgs.User" user "User.Drawings")
		(19 "Cmts.User" user "User.Comments")
		(21 "Eco1.User" user "User.Eco1")
		(23 "Eco2.User" user "User.Eco2")
		(25 "Edge.Cuts" user)
		(27 "Margin" user)
		(31 "F.CrtYd" user "F.Courtyard")
		(29 "B.CrtYd" user "B.Courtyard")
		(35 "F.Fab" user)
		(33 "B.Fab" user)
	)
	(footprint "antmicro-footprints:R_0402_1005Metric"
		(layer "B.Cu")
		(at 198.491252 91.55)
		(descr "Resistor SMD 0402")
		(tags "resistor SMD 0402")
		(property "Reference" "R209"
			(at 1.483748 -4.6 180)
			(layer "B.SilkS")
			(effects
				(font
					(size 0.7 0.7)
					(thickness 0.15)
				)
				(justify left bottom mirror)
			)
		)
		(property "Value" "R_2k2_0402"
			(at 0 -1.4 180)
			(layer "B.Fab")
			(effects
				(font
					(size 0.7 0.7)
					(thickness 0.15)
				)
				(justify left bottom mirror)
			)
		)
		(property "Description" "SMD Chip Resistor, 2.2 kohm, ± 1%, 62.5 mW, 0402 [1005 Metric], Thick Film, General Purpose"
			(at 0 0 0)
			(layer "F.Fab")
			(hide yes)
			(effects
				(font
					(size 1.27 1.27)
					(thickness 0.15)
				)
			)
		)
		(property "Author" "Antmicro"
			(at 0 0 0)
			(layer "B.Fab")
			(hide yes)
			(effects
				(font
					(size 1 1)
					(thickness 0.15)
				)
				(justify mirror)
			)
		)
		(property "DNP" "DNP"
			(at 0 0 0)
			(layer "B.Fab")
			(hide yes)
			(effects
				(font
					(size 1 1)
					(thickness 0.15)
				)
				(justify mirror)
			)
		)
		(property "License" "Apache-2.0"
			(at 0 0 0)
			(layer "B.Fab")
			(hide yes)
			(effects
				(font
					(size 1 1)
					(thickness 0.15)
				)
				(justify mirror)
			)
		)
		(property "MPN" "CR0402-FX-2201GLF"
			(at 0 0 0)
			(layer "B.Fab")
			(hide yes)
			(effects
				(font
					(size 1 1)
					(thickness 0.15)
				)
				(justify mirror)
			)
		)
		(property "Manufacturer" "Bourns"
			(at 0 0 0)
			(layer "B.Fab")
			(hide yes)
			(effects
				(font
					(size 1 1)
					(thickness 0.15)
				)
				(justify mirror)
			)
		)
		(property "Tolerance" "1%"
			(at 0 0 0)
			(layer "B.Fab")
			(hide yes)
			(effects
				(font
					(size 1 1)
					(thickness 0.15)
				)
				(justify mirror)
			)
		)
		(property "Val" "2k2"
			(at 0 0 0)
			(layer "B.Fab")
			(hide yes)
			(effects
				(font
					(size 1 1)
					(thickness 0.15)
				)
				(justify mirror)
			)
		)
		(property "dnp" ""
			(at 0 0 0)
			(layer "B.Fab")
			(hide yes)
			(effects
				(font
					(size 1 1)
					(thickness 0.15)
				)
				(justify mirror)
			)
		)
		(property "exclude_from_bom" ""
			(at 0 0 0)
			(layer "B.Fab")
			(hide yes)
			(effects
				(font
					(size 1 1)
					(thickness 0.15)
				)
				(justify mirror)
			)
		)
		(sheetname "HDMI + Ethernet")
		(sheetfile "hdmi-ethernet.kicad_sch")
		(attr smd exclude_from_bom)
		(fp_rect
			(start -0.925 0.47)
			(end 0.925 -0.47)
			(stroke
				(width 0.05)
				(type default)
			)
			(fill no)
			(layer "B.CrtYd")
		)
		(fp_rect
			(start -0.5 0.25)
			(end 0.5 -0.25)
			(stroke
				(width 0.15)
				(type solid)
			)
			(fill no)
			(layer "B.Fab")
		)
		(pad "1" smd roundrect
			(at -0.48 0)
			(size 0.59 0.64)
			(layers "B.Cu" "B.Mask" "B.Paste")
			(roundrect_rratio 0.25)
			(net 503 "/FPGA Bank 16 & 17/GBE_RGMII.RXD3")
			(pintype "passive")
		)
		(pad "2" smd roundrect
			(at 0.48 0)
			(size 0.59 0.64)
			(layers "B.Cu" "B.Mask" "B.Paste")
			(roundrect_rratio 0.25)
			(net 1 "GND")
			(pintype "passive")
		)
	)
	(footprint "antmicro-footprints:C_0201"
		(layer "B.Cu")
		(at 189.8 125.5 180)
		(descr "Capacitor SMD 0201")
		(tags "capacitor SMD 0201")
		(property "Reference" "C153"
			(at 0.5 -0.4 0)
			(layer "B.SilkS")
			(effects
				(font
					(size 0.7 0.7)
					(thickness 0.15)
				)
				(justify left bottom mirror)
			)
		)
		(property "Value" "C_100n_0201"
			(at 0 -1.4 0)
			(layer "B.Fab")
			(effects
				(font
					(size 0.7 0.7)
					(thickness 0.15)
				)
				(justify left bottom mirror)
			)
		)
		(property "Description" "SMD Multilayer Ceramic Capacitor, 0.1 µF, 6.3 V, 0201 [0603 Metric], ± 10%, X6S, CC Series"
			(at 0 0 180)
			(layer "F.Fab")
			(hide yes)
			(effects
				(font
					(size 1.27 1.27)
					(thickness 0.15)
				)
			)
		)
		(property "Author" "Antmicro"
			(at 379.6 251 0)
			(layer "B.Fab")
			(hide yes)
			(effects
				(font
					(size 1 1)
					(thickness 0.15)
				)
				(justify mirror)
			)
		)
		(property "Dielectric" ""
			(at 379.6 251 0)
			(layer "B.Fab")
			(hide yes)
			(effects
				(font
					(size 1 1)
					(thickness 0.15)
				)
				(justify mirror)
			)
		)
		(property "License" "Apache-2.0"
			(at 379.6 251 0)
			(layer "B.Fab")
			(hide yes)
			(effects
				(font
					(size 1 1)
					(thickness 0.15)
				)
				(justify mirror)
			)
		)
		(property "MPN" "CC0201KRX6S5BB104"
			(at 379.6 251 0)
			(layer "B.Fab")
			(hide yes)
			(effects
				(font
					(size 1 1)
					(thickness 0.15)
				)
				(justify mirror)
			)
		)
		(property "Manufacturer" "YAGEO"
			(at 379.6 251 0)
			(layer "B.Fab")
			(hide yes)
			(effects
				(font
					(size 1 1)
					(thickness 0.15)
				)
				(justify mirror)
			)
		)
		(property "Val" "100n"
			(at 379.6 251 0)
			(layer "B.Fab")
			(hide yes)
			(effects
				(font
					(size 1 1)
					(thickness 0.15)
				)
				(justify mirror)
			)
		)
		(property "Voltage" ""
			(at 379.6 251 0)
			(layer "B.Fab")
			(hide yes)
			(effects
				(font
					(size 1 1)
					(thickness 0.15)
				)
				(justify mirror)
			)
		)
		(sheetname "FPGA supply")
		(sheetfile "fpga-supply.kicad_sch")
		(attr smd)
		(fp_rect
			(start -0.7 0.35)
			(end 0.7 -0.35)
			(stroke
				(width 0.05)
				(type default)
			)
			(fill no)
			(layer "B.CrtYd")
		)
		(fp_rect
			(start 0.3 -0.15)
			(end -0.301 0.149)
			(stroke
				(width 0.15)
				(type solid)
			)
			(fill no)
			(layer "B.Fab")
		)
		(pad "" smd roundrect
			(at -0.349 0.002 180)
			(size 0.318 0.36)
			(layers "B.Paste")
			(roundrect_rratio 0.25)
		)
		(pad "" smd roundrect
			(at 0.341 0.002 180)
			(size 0.318 0.36)
			(layers "B.Paste")
			(roundrect_rratio 0.25)
		)
		(pad "1" smd roundrect
			(at -0.321 0.002 180)
			(size 0.46 0.4)
			(layers "B.Cu" "B.Mask")
			(roundrect_rratio 0.25)
			(net 1 "GND")
			(pintype "passive")
		)
		(pad "2" smd roundrect
			(at 0.32 0.002 180)
			(size 0.46 0.4)
			(layers "B.Cu" "B.Mask")
			(roundrect_rratio 0.25)
			(net 8 "+1V2_MGTAVTT")
			(pintype "passive")
		)
	)
	(footprint "antmicro-footprints:C_0402_1005Metric"
		(layer "B.Cu")
		(at 205 120.5)
		(descr "Capacitor SMD 0402")
		(tags "capacitor SMD 0402")
		(property "Reference" "C98"
			(at 29.35 -29.575 180)
			(layer "B.SilkS")
			(effects
				(font
					(size 0.7 0.7)
					(thickness 0.15)
				)
				(justify left bottom mirror)
			)
		)
		(property "Value" "C_100n_0402"
			(at 0 -1.169 180)
			(layer "B.Fab")
			(effects
				(font
					(size 0.7 0.7)
					(thickness 0.15)
				)
				(justify left bottom mirror)
			)
		)
		(property "Description" "SMD Multilayer Ceramic Capacitor, 0.1 µF, 50 V, 0402 [1005 Metric], ± 10%, X5R, GRM Series"
			(at 0 0 0)
			(layer "F.Fab")
			(hide yes)
			(effects
				(font
					(size 1.27 1.27)
					(thickness 0.15)
				)
			)
		)
		(property "Author" "Antmicro"
			(at 0 0 0)
			(layer "B.Fab")
			(hide yes)
			(effects
				(font
					(size 1 1)
					(thickness 0.15)
				)
				(justify mirror)
			)
		)
		(property "Dielectric" "X5R"
			(at 0 0 0)
			(layer "B.Fab")
			(hide yes)
			(effects
				(font
					(size 1 1)
					(thickness 0.15)
				)
				(justify mirror)
			)
		)
		(property "License" "Apache-2.0"
			(at 0 0 0)
			(layer "B.Fab")
			(hide yes)
			(effects
				(font
					(size 1 1)
					(thickness 0.15)
				)
				(justify mirror)
			)
		)
		(property "MPN" "GRM155R61H104KE14D"
			(at 0 0 0)
			(layer "B.Fab")
			(hide yes)
			(effects
				(font
					(size 1 1)
					(thickness 0.15)
				)
				(justify mirror)
			)
		)
		(property "Manufacturer" "Murata"
			(at 0 0 0)
			(layer "B.Fab")
			(hide yes)
			(effects
				(font
					(size 1 1)
					(thickness 0.15)
				)
				(justify mirror)
			)
		)
		(property "Val" "100n"
			(at 0 0 0)
			(layer "B.Fab")
			(hide yes)
			(effects
				(font
					(size 1 1)
					(thickness 0.15)
				)
				(justify mirror)
			)
		)
		(property "Voltage" "50V"
			(at 0 0 0)
			(layer "B.Fab")
			(hide yes)
			(effects
				(font
					(size 1 1)
					(thickness 0.15)
				)
				(justify mirror)
			)
		)
		(sheetname "FPGA Bank 16 & 17")
		(sheetfile "fpga-bank-16-17.kicad_sch")
		(attr smd)
		(fp_rect
			(start -0.925 0.47)
			(end 0.925 -0.47)
			(stroke
				(width 0.05)
				(type default)
			)
			(fill no)
			(layer "B.CrtYd")
		)
		(fp_line
			(start -0.494 -0.248)
			(end -0.494 0.25)
			(stroke
				(width 0.15)
				(type solid)
			)
			(layer "B.Fab")
		)
		(fp_line
			(start -0.494 0.25)
			(end 0.504 0.25)
			(stroke
				(width 0.15)
				(type solid)
			)
			(layer "B.Fab")
		)
		(fp_line
			(start 0.504 -0.248)
			(end -0.494 -0.248)
			(stroke
				(width 0.15)
				(type solid)
			)
			(layer "B.Fab")
		)
		(fp_line
			(start 0.504 0.25)
			(end 0.504 -0.248)
			(stroke
				(width 0.15)
				(type solid)
			)
			(layer "B.Fab")
		)
		(pad "1" smd roundrect
			(at -0.48 0)
			(size 0.59 0.64)
			(layers "B.Cu" "B.Mask" "B.Paste")
			(roundrect_rratio 0.25)
			(net 1 "GND")
			(pintype "passive")
		)
		(pad "2" smd roundrect
			(at 0.48 0)
			(size 0.59 0.64)
			(layers "B.Cu" "B.Mask" "B.Paste")
			(roundrect_rratio 0.25)
			(net 24 "+3V3")
			(pintype "passive")
		)
	)
	(footprint "antmicro-footprints:R_0402_1005Metric"
		(layer "B.Cu")
		(at 242.301 114.3 90)
		(descr "Resistor SMD 0402")
		(tags "resistor SMD 0402")
		(property "Reference" "R168"
			(at 1.375 1.274 270)
			(layer "B.SilkS")
			(effects
				(font
					(size 0.7 0.7)
					(thickness 0.15)
				)
				(justify left bottom mirror)
			)
		)
		(property "Value" "R_100k_0402"
			(at 0 -1.4 270)
			(layer "B.Fab")
			(effects
				(font
					(size 0.7 0.7)
					(thickness 0.15)
				)
				(justify left bottom mirror)
			)
		)
		(property "Description" "SMD Chip Resistor, 100 kohm, ± 1%, 62.5 mW, 0402 [1005 Metric], Thick Film, General Purpose"
			(at 0 0 90)
			(layer "F.Fab")
			(hide yes)
			(effects
				(font
					(size 1.27 1.27)
					(thickness 0.15)
				)
			)
		)
		(property "Author" "Antmicro"
			(at 356.601 -128.001 0)
			(layer "B.Fab")
			(hide yes)
			(effects
				(font
					(size 1 1)
					(thickness 0.15)
				)
				(justify mirror)
			)
		)
		(property "License" "Apache-2.0"
			(at 356.601 -128.001 0)
			(layer "B.Fab")
			(hide yes)
			(effects
				(font
					(size 1 1)
					(thickness 0.15)
				)
				(justify mirror)
			)
		)
		(property "MPN" "CR0402-FX-1003GLF"
			(at 356.601 -128.001 0)
			(layer "B.Fab")
			(hide yes)
			(effects
				(font
					(size 1 1)
					(thickness 0.15)
				)
				(justify mirror)
			)
		)
		(property "Manufacturer" "Bourns"
			(at 356.601 -128.001 0)
			(layer "B.Fab")
			(hide yes)
			(effects
				(font
					(size 1 1)
					(thickness 0.15)
				)
				(justify mirror)
			)
		)
		(property "Tolerance" "1%"
			(at 356.601 -128.001 0)
			(layer "B.Fab")
			(hide yes)
			(effects
				(font
					(size 1 1)
					(thickness 0.15)
				)
				(justify mirror)
			)
		)
		(property "Val" "100k"
			(at 356.601 -128.001 0)
			(layer "B.Fab")
			(hide yes)
			(effects
				(font
					(size 1 1)
					(thickness 0.15)
				)
				(justify mirror)
			)
		)
		(sheetname "User GPIO + LED + button + DIP switch")
		(sheetfile "user-gpio.kicad_sch")
		(attr smd)
		(fp_rect
			(start -0.925 0.47)
			(end 0.925 -0.47)
			(stroke
				(width 0.05)
				(type default)
			)
			(fill no)
			(layer "B.CrtYd")
		)
		(fp_rect
			(start -0.5 0.25)
			(end 0.5 -0.25)
			(stroke
				(width 0.15)
				(type solid)
			)
			(fill no)
			(layer "B.Fab")
		)
		(pad "1" smd roundrect
			(at -0.48 0 90)
			(size 0.59 0.64)
			(layers "B.Cu" "B.Mask" "B.Paste")
			(roundrect_rratio 0.25)
			(net 29 "Net-(J4-Pin_4)")
			(pintype "passive")
		)
		(pad "2" smd roundrect
			(at 0.48 0 90)
			(size 0.59 0.64)
			(layers "B.Cu" "B.Mask" "B.Paste")
			(roundrect_rratio 0.25)
			(net 703 "+5V")
			(pintype "passive")
		)
	)
	(footprint "antmicro-footprints:C_0402_1005Metric"
		(layer "B.Cu")
		(at 159.55 146.5 -90)
		(descr "Capacitor SMD 0402")
		(tags "capacitor SMD 0402")
		(property "Reference" "C174"
			(at -1.025 3.475 90)
			(layer "B.SilkS")
			(effects
				(font
					(size 0.7 0.7)
					(thickness 0.15)
				)
				(justify left bottom mirror)
			)
		)
		(property "Value" "C_100n_0402"
			(at 0 -1.169 90)
			(layer "B.Fab")
			(effects
				(font
					(size 0.7 0.7)
					(thickness 0.15)
				)
				(justify left bottom mirror)
			)
		)
		(property "Description" "SMD Multilayer Ceramic Capacitor, 0.1 µF, 50 V, 0402 [1005 Metric], ± 10%, X5R, GRM Series"
			(at 0 0 270)
			(layer "F.Fab")
			(hide yes)
			(effects
				(font
					(size 1.27 1.27)
					(thickness 0.15)
				)
			)
		)
		(property "Author" "Antmicro"
			(at 13.05 306.05 0)
			(layer "B.Fab")
			(hide yes)
			(effects
				(font
					(size 1 1)
					(thickness 0.15)
				)
				(justify mirror)
			)
		)
		(property "Dielectric" "X5R"
			(at 13.05 306.05 0)
			(layer "B.Fab")
			(hide yes)
			(effects
				(font
					(size 1 1)
					(thickness 0.15)
				)
				(justify mirror)
			)
		)
		(property "License" "Apache-2.0"
			(at 13.05 306.05 0)
			(layer "B.Fab")
			(hide yes)
			(effects
				(font
					(size 1 1)
					(thickness 0.15)
				)
				(justify mirror)
			)
		)
		(property "MPN" "GRM155R61H104KE14D"
			(at 13.05 306.05 0)
			(layer "B.Fab")
			(hide yes)
			(effects
				(font
					(size 1 1)
					(thickness 0.15)
				)
				(justify mirror)
			)
		)
		(property "Manufacturer" "Murata"
			(at 13.05 306.05 0)
			(layer "B.Fab")
			(hide yes)
			(effects
				(font
					(size 1 1)
					(thickness 0.15)
				)
				(justify mirror)
			)
		)
		(property "Val" "100n"
			(at 13.05 306.05 0)
			(layer "B.Fab")
			(hide yes)
			(effects
				(font
					(size 1 1)
					(thickness 0.15)
				)
				(justify mirror)
			)
		)
		(property "Voltage" "50V"
			(at 13.05 306.05 0)
			(layer "B.Fab")
			(hide yes)
			(effects
				(font
					(size 1 1)
					(thickness 0.15)
				)
				(justify mirror)
			)
		)
		(sheetname "DRAM + SRAM")
		(sheetfile "ram.kicad_sch")
		(attr smd)
		(fp_rect
			(start -0.925 0.47)
			(end 0.925 -0.47)
			(stroke
				(width 0.05)
				(type default)
			)
			(fill no)
			(layer "B.CrtYd")
		)
		(fp_line
			(start -0.494 0.25)
			(end 0.504 0.25)
			(stroke
				(width 0.15)
				(type solid)
			)
			(layer "B.Fab")
		)
		(fp_line
			(start 0.504 0.25)
			(end 0.504 -0.248)
			(stroke
				(width 0.15)
				(type solid)
			)
			(layer "B.Fab")
		)
		(fp_line
			(start -0.494 -0.248)
			(end -0.494 0.25)
			(stroke
				(width 0.15)
				(type solid)
			)
			(layer "B.Fab")
		)
		(fp_line
			(start 0.504 -0.248)
			(end -0.494 -0.248)
			(stroke
				(width 0.15)
				(type solid)
			)
			(layer "B.Fab")
		)
		(pad "1" smd roundrect
			(at -0.48 0 270)
			(size 0.59 0.64)
			(layers "B.Cu" "B.Mask" "B.Paste")
			(roundrect_rratio 0.25)
			(net 7 "+0V675_VTT")
			(pintype "passive")
		)
		(pad "2" smd roundrect
			(at 0.48 0 270)
			(size 0.59 0.64)
			(layers "B.Cu" "B.Mask" "B.Paste")
			(roundrect_rratio 0.25)
			(net 25 "+1V35")
			(pintype "passive")
		)
	)
	(footprint "antmicro-footprints:R_0402_1005Metric"
		(layer "B.Cu")
		(at 258.4 88.6 -90)
		(descr "Resistor SMD 0402")
		(tags "resistor SMD 0402")
		(property "Reference" "R355"
			(at -1.35 -1.25 90)
			(layer "B.SilkS")
			(effects
				(font
					(size 0.7 0.7)
					(thickness 0.15)
				)
				(justify left bottom mirror)
			)
		)
		(property "Value" "R_100k_0402"
			(at 0 -1.4 90)
			(layer "B.Fab")
			(effects
				(font
					(size 0.7 0.7)
					(thickness 0.15)
				)
				(justify left bottom mirror)
			)
		)
		(property "Description" "SMD Chip Resistor, 100 kohm, ± 1%, 62.5 mW, 0402 [1005 Metric], Thick Film, General Purpose"
			(at 0 0 270)
			(layer "F.Fab")
			(hide yes)
			(effects
				(font
					(size 1.27 1.27)
					(thickness 0.15)
				)
			)
		)
		(property "Author" "Antmicro"
			(at 169.8 347 0)
			(layer "B.Fab")
			(hide yes)
			(effects
				(font
					(size 1 1)
					(thickness 0.15)
				)
				(justify mirror)
			)
		)
		(property "License" "Apache-2.0"
			(at 169.8 347 0)
			(layer "B.Fab")
			(hide yes)
			(effects
				(font
					(size 1 1)
					(thickness 0.15)
				)
				(justify mirror)
			)
		)
		(property "MPN" "CR0402-FX-1003GLF"
			(at 169.8 347 0)
			(layer "B.Fab")
			(hide yes)
			(effects
				(font
					(size 1 1)
					(thickness 0.15)
				)
				(justify mirror)
			)
		)
		(property "Manufacturer" "Bourns"
			(at 169.8 347 0)
			(layer "B.Fab")
			(hide yes)
			(effects
				(font
					(size 1 1)
					(thickness 0.15)
				)
				(justify mirror)
			)
		)
		(property "Tolerance" "1%"
			(at 169.8 347 0)
			(layer "B.Fab")
			(hide yes)
			(effects
				(font
					(size 1 1)
					(thickness 0.15)
				)
				(justify mirror)
			)
		)
		(property "Val" "100k"
			(at 169.8 347 0)
			(layer "B.Fab")
			(hide yes)
			(effects
				(font
					(size 1 1)
					(thickness 0.15)
				)
				(justify mirror)
			)
		)
		(sheetname "User GPIO + LED + button + DIP switch")
		(sheetfile "user-gpio.kicad_sch")
		(attr smd)
		(fp_rect
			(start -0.925 0.47)
			(end 0.925 -0.47)
			(stroke
				(width 0.05)
				(type default)
			)
			(fill no)
			(layer "B.CrtYd")
		)
		(fp_rect
			(start -0.5 0.25)
			(end 0.5 -0.25)
			(stroke
				(width 0.15)
				(type solid)
			)
			(fill no)
			(layer "B.Fab")
		)
		(pad "1" smd roundrect
			(at -0.48 0 270)
			(size 0.59 0.64)
			(layers "B.Cu" "B.Mask" "B.Paste")
			(roundrect_rratio 0.25)
			(net 1301 "/USER_IO.LED_GREEN2")
			(pintype "passive")
		)
		(pad "2" smd roundrect
			(at 0.48 0 270)
			(size 0.59 0.64)
			(layers "B.Cu" "B.Mask" "B.Paste")
			(roundrect_rratio 0.25)
			(net 1 "GND")
			(pintype "passive")
		)
	)
)
